# SCM (Grand Teton) — schematic netlist excerpt (pin names and nets, part order shuffled) for the footprints in the layout excerpt that follows; sources: Cadence DE-HDL packaged netlist, KiCad conversion of 12092022_DA0F0TMDCD0_F0T_Management_Board_D_brd_V3_OCP.brd

R391  Q_RES  8.2K 5% EMPTY  pkg 0402LF  page 50 : A = P3V3_AUX ; B = REAR_AC_PWR_BTN_N
R757  Q_RES  33.2 1% CHIP  pkg 0402LF  page 30 : A = UART_BMC_5_RXD_BUF1_R ; B = UART_BMC_5_RXD_R

(kicad_pcb
	(version 20260206)
	(generator "pcbnew")
	(generator_version "10.0")
	(general
		(thickness 1.6)
		(legacy_teardrops no)
	)
	(paper "A4")
	(title_block
		(title "12092022_DA0F0TMDCD0_F0T_Management_Board_D_brd_V3_OCP.brd")
		(comment 1 "Grand Teton / footprints 624-625 of 1440")
	)
	(layers
		(0 "F.Cu" signal "TOP")
		(4 "In1.Cu" signal "GND")
		(6 "In2.Cu" signal "IN1")
		(8 "In3.Cu" signal "GND1")
		(10 "In4.Cu" signal "IN2")
		(12 "In5.Cu" signal "VCC")
		(14 "In6.Cu" signal "VCC1")
		(16 "In7.Cu" signal "IN3")
		(18 "In8.Cu" signal "GND2")
		(20 "In9.Cu" signal "IN4")
		(22 "In10.Cu" signal "GND3")
		(2 "B.Cu" signal "BOTTOM")
		(9 "F.Adhes" user "F.Adhesive")
		(11 "B.Adhes" user "B.Adhesive")
		(13 "F.Paste" user "Package Geometry/Pastemask Top")
		(15 "B.Paste" user "Package Geometry/Pastemask Bottom")
		(5 "F.SilkS" user "Ref Des/Silkscreen Top")
		(7 "B.SilkS" user "Ref Des/Silkscreen Bottom")
		(1 "F.Mask" user "Board Geometry/Soldermask Top")
		(3 "B.Mask" user "Board Geometry/Soldermask Bottom")
		(17 "Dwgs.User" user "User.Drawings")
		(19 "Cmts.User" user "User.Comments")
		(21 "Eco1.User" user "User.Eco1")
		(23 "Eco2.User" user "User.Eco2")
		(25 "Edge.Cuts" user "Board Geometry/Outline")
		(27 "Margin" user)
		(31 "F.CrtYd" user "Package Geometry/Place Bound Top")
		(29 "B.CrtYd" user "Package Geometry/Place Bound Bottom")
		(35 "F.Fab" user "Ref Des/Assembly Top")
		(33 "B.Fab" user "Ref Des/Assembly Bottom")
	)
	(footprint ""
		(layer "F.Cu")
		(at 31.623 -66.7258 90)
		(property "Reference" "R757"
			(at 0 0 90)
			(layer "F.SilkS")
			(hide yes)
			(effects
				(font
					(size 1.27 1.27)
				)
			)
		)
		(property "Value" ""
			(at 0 0 90)
			(layer "F.Fab")
			(effects
				(font
					(size 1.27 1.27)
				)
			)
		)
		(duplicate_pad_numbers_are_jumpers no)
		(fp_line
			(start 0.7874 -0.4064)
			(end 0.7874 0.4064)
			(stroke
				(width 0.1524)
				(type default)
			)
			(layer "F.SilkS")
		)
		(fp_line
			(start -0.7874 -0.4064)
			(end 0.7874 -0.4064)
			(stroke
				(width 0.1524)
				(type default)
			)
			(layer "F.SilkS")
		)
		(fp_line
			(start 0.7874 0.4064)
			(end -0.7874 0.4064)
			(stroke
				(width 0.1524)
				(type default)
			)
			(layer "F.SilkS")
		)
		(fp_line
			(start -0.7874 0.4064)
			(end -0.7874 -0.4064)
			(stroke
				(width 0.1524)
				(type default)
			)
			(layer "F.SilkS")
		)
		(fp_line
			(start -0.12065 -0.305054)
			(end -0.12065 -0.2794)
			(stroke
				(width 0.1)
				(type default)
			)
			(layer "F.Fab")
		)
		(fp_line
			(start -0.67945 -0.305054)
			(end -0.12065 -0.305054)
			(stroke
				(width 0.1)
				(type default)
			)
			(layer "F.Fab")
		)
		(fp_line
			(start 0.67945 -0.3048)
			(end 0.67945 0.3048)
			(stroke
				(width 0.1)
				(type default)
			)
			(layer "F.Fab")
		)
		(fp_line
			(start 0.12065 -0.3048)
			(end 0.67945 -0.3048)
			(stroke
				(width 0.1)
				(type default)
			)
			(layer "F.Fab")
		)
		(fp_line
			(start 0.12065 -0.2794)
			(end 0.12065 -0.3048)
			(stroke
				(width 0.1)
				(type default)
			)
			(layer "F.Fab")
		)
		(fp_line
			(start -0.12065 -0.2794)
			(end 0.12065 -0.2794)
			(stroke
				(width 0.1)
				(type default)
			)
			(layer "F.Fab")
		)
		(fp_line
			(start 0.120396 0.2794)
			(end -0.12065 0.2794)
			(stroke
				(width 0.1)
				(type default)
			)
			(layer "F.Fab")
		)
		(fp_line
			(start -0.12065 0.2794)
			(end -0.12065 0.3048)
			(stroke
				(width 0.1)
				(type default)
			)
			(layer "F.Fab")
		)
		(fp_line
			(start 0.67945 0.3048)
			(end 0.120396 0.3048)
			(stroke
				(width 0.1)
				(type default)
			)
			(layer "F.Fab")
		)
		(fp_line
			(start 0.120396 0.3048)
			(end 0.120396 0.2794)
			(stroke
				(width 0.1)
				(type default)
			)
			(layer "F.Fab")
		)
		(fp_line
			(start -0.12065 0.3048)
			(end -0.67945 0.3048)
			(stroke
				(width 0.1)
				(type default)
			)
			(layer "F.Fab")
		)
		(fp_line
			(start -0.67945 0.3048)
			(end -0.67945 -0.305054)
			(stroke
				(width 0.1)
				(type default)
			)
			(layer "F.Fab")
		)
		(pad "1" smd circle
			(at -0.40005 0 90)
			(size 0 0)
			(layers "F.Cu" "F.Mask" "F.Paste")
			(net "UART_BMC_5_RXD_BUF1_R")
		)
		(pad "2" smd circle
			(at 0.40005 0 90)
			(size 0 0)
			(layers "F.Cu" "F.Mask" "F.Paste")
			(net "UART_BMC_5_RXD_R")
		)
	)
	(footprint ""
		(layer "F.Cu")
		(at 73.66 -16.256 -90)
		(property "Reference" "R391"
			(at 0 0 270)
			(layer "F.SilkS")
			(hide yes)
			(effects
				(font
					(size 1.27 1.27)
				)
			)
		)
		(property "Value" ""
			(at 0 0 270)
			(layer "F.Fab")
			(effects
				(font
					(size 1.27 1.27)
				)
			)
		)
		(duplicate_pad_numbers_are_jumpers no)
		(fp_line
			(start -0.7874 0.4064)
			(end -0.7874 -0.4064)
			(stroke
				(width 0.1524)
				(type default)
			)
			(layer "F.SilkS")
		)
		(fp_line
			(start 0.7874 0.4064)
			(end -0.7874 0.4064)
			(stroke
				(width 0.1524)
				(type default)
			)
			(layer "F.SilkS")
		)
		(fp_line
			(start -0.7874 -0.4064)
			(end 0.7874 -0.4064)
			(stroke
				(width 0.1524)
				(type default)
			)
			(layer "F.SilkS")
		)
		(fp_line
			(start 0.7874 -0.4064)
			(end 0.7874 0.4064)
			(stroke
				(width 0.1524)
				(type default)
			)
			(layer "F.SilkS")
		)
		(fp_line
			(start -0.67945 0.3048)
			(end -0.67945 -0.305054)
			(stroke
				(width 0.1)
				(type default)
			)
			(layer "F.Fab")
		)
		(fp_line
			(start -0.12065 0.3048)
			(end -0.67945 0.3048)
			(stroke
				(width 0.1)
				(type default)
			)
			(layer "F.Fab")
		)
		(fp_line
			(start 0.120396 0.3048)
			(end 0.120396 0.2794)
			(stroke
				(width 0.1)
				(type default)
			)
			(layer "F.Fab")
		)
		(fp_line
			(start 0.67945 0.3048)
			(end 0.120396 0.3048)
			(stroke
				(width 0.1)
				(type default)
			)
			(layer "F.Fab")
		)
		(fp_line
			(start -0.12065 0.2794)
			(end -0.12065 0.3048)
			(stroke
				(width 0.1)
				(type default)
			)
			(layer "F.Fab")
		)
		(fp_line
			(start 0.120396 0.2794)
			(end -0.12065 0.2794)
			(stroke
				(width 0.1)
				(type default)
			)
			(layer "F.Fab")
		)
		(fp_line
			(start -0.12065 -0.2794)
			(end 0.12065 -0.2794)
			(stroke
				(width 0.1)
				(type default)
			)
			(layer "F.Fab")
		)
		(fp_line
			(start 0.12065 -0.2794)
			(end 0.12065 -0.3048)
			(stroke
				(width 0.1)
				(type default)
			)
			(layer "F.Fab")
		)
		(fp_line
			(start 0.12065 -0.3048)
			(end 0.67945 -0.3048)
			(stroke
				(width 0.1)
				(type default)
			)
			(layer "F.Fab")
		)
		(fp_line
			(start 0.67945 -0.3048)
			(end 0.67945 0.3048)
			(stroke
				(width 0.1)
				(type default)
			)
			(layer "F.Fab")
		)
		(fp_line
			(start -0.67945 -0.305054)
			(end -0.12065 -0.305054)
			(stroke
				(width 0.1)
				(type default)
			)
			(layer "F.Fab")
		)
		(fp_line
			(start -0.12065 -0.305054)
			(end -0.12065 -0.2794)
			(stroke
				(width 0.1)
				(type default)
			)
			(layer "F.Fab")
		)
		(pad "1" smd circle
			(at -0.40005 0 270)
			(size 0 0)
			(layers "F.Cu" "F.Mask" "F.Paste")
			(net "P3V3_AUX")
		)
		(pad "2" smd circle
			(at 0.40005 0 270)
			(size 0 0)
			(layers "F.Cu" "F.Mask" "F.Paste")
			(net "REAR_AC_PWR_BTN_N")
		)
	)
)
